(kicad_pcb
	(version 20260206)
	(generator "pcbnew")
	(generator_version "10.0")
	(general
		(thickness 1.6)
		(legacy_teardrops no)
	)
	(paper "A4")
	(title_block
		(title "Bryce Canyon_SCC_16316-1_OCP.brd")
		(comment 1 "Bryce Canyon / footprints 809-816 of 1561")
	)
	(layers
		(0 "F.Cu" signal "TOP")
		(4 "In1.Cu" signal "L2GND")
		(6 "In2.Cu" signal "L3")
		(8 "In3.Cu" signal "L4VCC")
		(10 "In4.Cu" signal "L5VCC")
		(12 "In5.Cu" signal "L6")
		(14 "In6.Cu" signal "L7GND")
		(2 "B.Cu" signal "BOTTOM")
		(9 "F.Adhes" user "F.Adhesive")
		(11 "B.Adhes" user "B.Adhesive")
		(13 "F.Paste" user "Package Geometry/Pastemask Top")
		(15 "B.Paste" user "Package Geometry/Pastemask Bottom")
		(5 "F.SilkS" user "Ref Des/Silkscreen Top")
		(7 "B.SilkS" user "Ref Des/Silkscreen Bottom")
		(1 "F.Mask" user "Board Geometry/Soldermask Top")
		(3 "B.Mask" user "Board Geometry/Soldermask Bottom")
		(17 "Dwgs.User" user "User.Drawings")
		(19 "Cmts.User" user "User.Comments")
		(21 "Eco1.User" user "User.Eco1")
		(23 "Eco2.User" user "User.Eco2")
		(25 "Edge.Cuts" user "Board Geometry/Outline")
		(27 "Margin" user)
		(31 "F.CrtYd" user "Package Geometry/Place Bound Top")
		(29 "B.CrtYd" user "Package Geometry/Place Bound Bottom")
		(35 "F.Fab" user "Ref Des/Assembly Top")
		(33 "B.Fab" user "Ref Des/Assembly Bottom")
	)
	(footprint ""
		(layer "B.Cu")
		(at 167.7543 -34.0614)
		(property "Reference" "C404"
			(at 0 0 0)
			(layer "B.SilkS")
			(hide yes)
			(effects
				(font
					(size 1.27 1.27)
				)
				(justify mirror)
			)
		)
		(property "Value" "SCD1U16V2KX-3GP"
			(at -1.1811 -2.7051 0)
			(unlocked yes)
			(layer "B.Fab")
			(hide yes)
			(effects
				(font
					(size 1.016 1.016)
					(thickness 0.1524)
				)
				(justify mirror)
			)
		)
		(property "Device Type" "C402H22"
			(at -1.1811 -4.2291 0)
			(unlocked yes)
			(layer "B.Fab")
			(hide yes)
			(effects
				(font
					(size 1.016 1.016)
					(thickness 0.1524)
				)
				(justify mirror)
			)
		)
		(duplicate_pad_numbers_are_jumpers no)
		(fp_rect
			(start 0.4318 0.9525)
			(end -0.4318 -0.9525)
			(stroke
				(width 0)
				(type default)
			)
			(fill no)
			(layer "B.CrtYd")
		)
		(fp_rect
			(start 0.4318 0.9525)
			(end -0.4318 -0.9525)
			(stroke
				(width 0)
				(type default)
			)
			(fill no)
			(layer "B.Fab")
		)
		(pad "1" smd custom
			(at 0 -0.4445 180)
			(size 0.1524 0.1524)
			(layers "B.Cu" "B.Mask" "B.Paste")
			(net "SAS0_AVDD")
			(options
				(clearance outline)
				(anchor circle)
			)
			(primitives
				(gr_poly
					(pts
						(arc
							(start 0.3048 0.2032)
							(mid 0.275042 0.275042)
							(end 0.2032 0.3048)
						)
						(arc
							(start -0.2032 0.3048)
							(mid -0.275042 0.275042)
							(end -0.3048 0.2032)
						)
						(arc
							(start -0.3048 -0.2032)
							(mid -0.275042 -0.275042)
							(end -0.2032 -0.3048)
						)
						(arc
							(start 0.2032 -0.3048)
							(mid 0.275042 -0.275042)
							(end 0.3048 -0.2032)
						)
					)
					(width 0)
					(fill yes)
				)
			)
		)
		(pad "2" smd custom
			(at 0 0.4445 180)
			(size 0.1524 0.1524)
			(layers "B.Cu" "B.Mask" "B.Paste")
			(net "GND")
			(options
				(clearance outline)
				(anchor circle)
			)
			(primitives
				(gr_poly
					(pts
						(arc
							(start 0.3048 0.2032)
							(mid 0.275042 0.275042)
							(end 0.2032 0.3048)
						)
						(arc
							(start -0.2032 0.3048)
							(mid -0.275042 0.275042)
							(end -0.3048 0.2032)
						)
						(arc
							(start -0.3048 -0.2032)
							(mid -0.275042 -0.275042)
							(end -0.2032 -0.3048)
						)
						(arc
							(start 0.2032 -0.3048)
							(mid 0.275042 -0.275042)
							(end 0.3048 -0.2032)
						)
					)
					(width 0)
					(fill yes)
				)
			)
		)
	)
	(footprint ""
		(layer "B.Cu")
		(at 124.7267 -72.5043 90)
		(property "Reference" "C582"
			(at 0 0 90)
			(layer "B.SilkS")
			(hide yes)
			(effects
				(font
					(size 1.27 1.27)
				)
				(justify mirror)
			)
		)
		(property "Value" "SCD1U6D3V1KX-GP"
			(at 2.8321 -1.7399 90)
			(unlocked yes)
			(layer "B.Fab")
			(hide yes)
			(effects
				(font
					(size 1.016 1.016)
					(thickness 0.1524)
				)
				(justify mirror)
			)
		)
		(property "Device Type" "C0201H13"
			(at 2.8321 -3.2639 90)
			(unlocked yes)
			(layer "B.Fab")
			(hide yes)
			(effects
				(font
					(size 1.016 1.016)
					(thickness 0.1524)
				)
				(justify mirror)
			)
		)
		(duplicate_pad_numbers_are_jumpers no)
		(fp_rect
			(start 0.2794 0.6477)
			(end -0.2794 -0.6477)
			(stroke
				(width 0)
				(type default)
			)
			(fill no)
			(layer "B.CrtYd")
		)
		(fp_rect
			(start 0.2794 0.6477)
			(end -0.2794 -0.6477)
			(stroke
				(width 0)
				(type default)
			)
			(fill no)
			(layer "B.Fab")
		)
		(pad "1" smd custom
			(at 0 -0.2794 270)
			(size 0.0762 0.0762)
			(layers "B.Cu" "B.Mask" "B.Paste")
			(net "GB_VDDA")
			(options
				(clearance outline)
				(anchor circle)
			)
			(primitives
				(gr_poly
					(pts
						(arc
							(start 0.1524 0.127)
							(mid 0.137521 0.162921)
							(end 0.1016 0.1778)
						)
						(arc
							(start -0.1016 0.1778)
							(mid -0.137521 0.162921)
							(end -0.1524 0.127)
						)
						(arc
							(start -0.1524 -0.127)
							(mid -0.137521 -0.162921)
							(end -0.1016 -0.1778)
						)
						(arc
							(start 0.1016 -0.1778)
							(mid 0.137521 -0.162921)
							(end 0.1524 -0.127)
						)
					)
					(width 0)
					(fill yes)
				)
			)
		)
		(pad "2" smd custom
			(at 0 0.2794 270)
			(size 0.0762 0.0762)
			(layers "B.Cu" "B.Mask" "B.Paste")
			(net "GND")
			(options
				(clearance outline)
				(anchor circle)
			)
			(primitives
				(gr_poly
					(pts
						(arc
							(start 0.1524 0.127)
							(mid 0.137521 0.162921)
							(end 0.1016 0.1778)
						)
						(arc
							(start -0.1016 0.1778)
							(mid -0.137521 0.162921)
							(end -0.1524 0.127)
						)
						(arc
							(start -0.1524 -0.127)
							(mid -0.137521 -0.162921)
							(end -0.1016 -0.1778)
						)
						(arc
							(start 0.1016 -0.1778)
							(mid 0.137521 -0.162921)
							(end 0.1524 -0.127)
						)
					)
					(width 0)
					(fill yes)
				)
			)
		)
	)
	(footprint ""
		(layer "B.Cu")
		(at 114.5794 -80.4672 180)
		(property "Reference" "C145"
			(at 0 0 0)
			(layer "B.SilkS")
			(hide yes)
			(effects
				(font
					(size 1.27 1.27)
				)
				(justify mirror)
			)
		)
		(property "Value" "SCD1U6D3V1KX-GP"
			(at 2.8321 -1.7399 180)
			(unlocked yes)
			(layer "B.Fab")
			(hide yes)
			(effects
				(font
					(size 1.016 1.016)
					(thickness 0.1524)
				)
				(justify mirror)
			)
		)
		(property "Device Type" "C0201H13"
			(at 2.8321 -3.2639 180)
			(unlocked yes)
			(layer "B.Fab")
			(hide yes)
			(effects
				(font
					(size 1.016 1.016)
					(thickness 0.1524)
				)
				(justify mirror)
			)
		)
		(duplicate_pad_numbers_are_jumpers no)
		(fp_rect
			(start 0.2794 0.6477)
			(end -0.2794 -0.6477)
			(stroke
				(width 0)
				(type default)
			)
			(fill no)
			(layer "B.CrtYd")
		)
		(fp_rect
			(start 0.2794 0.6477)
			(end -0.2794 -0.6477)
			(stroke
				(width 0)
				(type default)
			)
			(fill no)
			(layer "B.Fab")
		)
		(pad "1" smd custom
			(at 0 -0.2794)
			(size 0.0762 0.0762)
			(layers "B.Cu" "B.Mask" "B.Paste")
			(net "P1V8_E")
			(options
				(clearance outline)
				(anchor circle)
			)
			(primitives
				(gr_poly
					(pts
						(arc
							(start 0.1524 0.127)
							(mid 0.137521 0.162921)
							(end 0.1016 0.1778)
						)
						(arc
							(start -0.1016 0.1778)
							(mid -0.137521 0.162921)
							(end -0.1524 0.127)
						)
						(arc
							(start -0.1524 -0.127)
							(mid -0.137521 -0.162921)
							(end -0.1016 -0.1778)
						)
						(arc
							(start 0.1016 -0.1778)
							(mid 0.137521 -0.162921)
							(end 0.1524 -0.127)
						)
					)
					(width 0)
					(fill yes)
				)
			)
		)
		(pad "2" smd custom
			(at 0 0.2794)
			(size 0.0762 0.0762)
			(layers "B.Cu" "B.Mask" "B.Paste")
			(net "GND")
			(options
				(clearance outline)
				(anchor circle)
			)
			(primitives
				(gr_poly
					(pts
						(arc
							(start 0.1524 0.127)
							(mid 0.137521 0.162921)
							(end 0.1016 0.1778)
						)
						(arc
							(start -0.1016 0.1778)
							(mid -0.137521 0.162921)
							(end -0.1524 0.127)
						)
						(arc
							(start -0.1524 -0.127)
							(mid -0.137521 -0.162921)
							(end -0.1016 -0.1778)
						)
						(arc
							(start 0.1016 -0.1778)
							(mid 0.137521 -0.162921)
							(end 0.1524 -0.127)
						)
					)
					(width 0)
					(fill yes)
				)
			)
		)
	)
	(footprint ""
		(layer "B.Cu")
		(at 121.9454 -93.345 90)
		(property "Reference" "R559"
			(at 0 0 90)
			(layer "B.SilkS")
			(hide yes)
			(effects
				(font
					(size 1.27 1.27)
				)
				(justify mirror)
			)
		)
		(property "Value" "10KR2F-2-GP"
			(at -0.064008 -3.993896 90)
			(unlocked yes)
			(layer "B.Fab")
			(hide yes)
			(effects
				(font
					(size 1.016 1.016)
					(thickness 0.1524)
				)
				(justify mirror)
			)
		)
		(property "Device Type" "R402H16"
			(at -0.064008 -5.517896 90)
			(unlocked yes)
			(layer "B.Fab")
			(hide yes)
			(effects
				(font
					(size 1.016 1.016)
					(thickness 0.1524)
				)
				(justify mirror)
			)
		)
		(duplicate_pad_numbers_are_jumpers no)
		(fp_line
			(start 0.508 -0.9398)
			(end 0.508 0.9398)
			(stroke
				(width 0.1524)
				(type default)
			)
			(layer "B.SilkS")
		)
		(fp_line
			(start -0.508 -0.9398)
			(end 0.508 -0.9398)
			(stroke
				(width 0.1524)
				(type default)
			)
			(layer "B.SilkS")
		)
		(fp_rect
			(start 0.508 0.9398)
			(end -0.508 -0.9398)
			(stroke
				(width 0)
				(type default)
			)
			(fill no)
			(layer "B.CrtYd")
		)
		(fp_rect
			(start 0.508 0.9398)
			(end -0.508 -0.9398)
			(stroke
				(width 0)
				(type default)
			)
			(fill no)
			(layer "B.Fab")
		)
		(pad "1" smd custom
			(at 0 -0.4445 270)
			(size 0.1397 0.1397)
			(layers "B.Cu" "B.Mask" "B.Paste")
			(net "SCC_RMT_HEARTBEAT_LS")
			(options
				(clearance outline)
				(anchor circle)
			)
			(primitives
				(gr_poly
					(pts
						(arc
							(start -0.1778 0.2794)
							(mid -0.249642 0.249642)
							(end -0.2794 0.1778)
						)
						(arc
							(start -0.2794 -0.1778)
							(mid -0.249642 -0.249642)
							(end -0.1778 -0.2794)
						)
						(arc
							(start 0.1778 -0.2794)
							(mid 0.249642 -0.249642)
							(end 0.2794 -0.1778)
						)
						(arc
							(start 0.2794 0.1778)
							(mid 0.249642 0.249642)
							(end 0.1778 0.2794)
						)
					)
					(width 0)
					(fill yes)
				)
			)
		)
		(pad "2" smd custom
			(at 0 0.4445 270)
			(size 0.1397 0.1397)
			(layers "B.Cu" "B.Mask" "B.Paste")
			(net "GND")
			(options
				(clearance outline)
				(anchor circle)
			)
			(primitives
				(gr_poly
					(pts
						(arc
							(start -0.1778 0.2794)
							(mid -0.249642 0.249642)
							(end -0.2794 0.1778)
						)
						(arc
							(start -0.2794 -0.1778)
							(mid -0.249642 -0.249642)
							(end -0.1778 -0.2794)
						)
						(arc
							(start 0.1778 -0.2794)
							(mid 0.249642 -0.249642)
							(end 0.2794 -0.1778)
						)
						(arc
							(start 0.2794 0.1778)
							(mid 0.249642 0.249642)
							(end 0.1778 0.2794)
						)
					)
					(width 0)
					(fill yes)
				)
			)
		)
	)
	(footprint ""
		(layer "B.Cu")
		(at 120.523 -76.454 180)
		(property "Reference" "C144"
			(at 0 0 0)
			(layer "B.SilkS")
			(hide yes)
			(effects
				(font
					(size 1.27 1.27)
				)
				(justify mirror)
			)
		)
		(property "Value" "SCD1U6D3V1KX-GP"
			(at 2.8321 -1.7399 180)
			(unlocked yes)
			(layer "B.Fab")
			(hide yes)
			(effects
				(font
					(size 1.016 1.016)
					(thickness 0.1524)
				)
				(justify mirror)
			)
		)
		(property "Device Type" "C0201H13"
			(at 2.8321 -3.2639 180)
			(unlocked yes)
			(layer "B.Fab")
			(hide yes)
			(effects
				(font
					(size 1.016 1.016)
					(thickness 0.1524)
				)
				(justify mirror)
			)
		)
		(duplicate_pad_numbers_are_jumpers no)
		(fp_rect
			(start 0.2794 0.6477)
			(end -0.2794 -0.6477)
			(stroke
				(width 0)
				(type default)
			)
			(fill no)
			(layer "B.CrtYd")
		)
		(fp_rect
			(start 0.2794 0.6477)
			(end -0.2794 -0.6477)
			(stroke
				(width 0)
				(type default)
			)
			(fill no)
			(layer "B.Fab")
		)
		(pad "1" smd custom
			(at 0 -0.2794)
			(size 0.0762 0.0762)
			(layers "B.Cu" "B.Mask" "B.Paste")
			(net "P1V8_E")
			(options
				(clearance outline)
				(anchor circle)
			)
			(primitives
				(gr_poly
					(pts
						(arc
							(start 0.1524 0.127)
							(mid 0.137521 0.162921)
							(end 0.1016 0.1778)
						)
						(arc
							(start -0.1016 0.1778)
							(mid -0.137521 0.162921)
							(end -0.1524 0.127)
						)
						(arc
							(start -0.1524 -0.127)
							(mid -0.137521 -0.162921)
							(end -0.1016 -0.1778)
						)
						(arc
							(start 0.1016 -0.1778)
							(mid 0.137521 -0.162921)
							(end 0.1524 -0.127)
						)
					)
					(width 0)
					(fill yes)
				)
			)
		)
		(pad "2" smd custom
			(at 0 0.2794)
			(size 0.0762 0.0762)
			(layers "B.Cu" "B.Mask" "B.Paste")
			(net "GND")
			(options
				(clearance outline)
				(anchor circle)
			)
			(primitives
				(gr_poly
					(pts
						(arc
							(start 0.1524 0.127)
							(mid 0.137521 0.162921)
							(end 0.1016 0.1778)
						)
						(arc
							(start -0.1016 0.1778)
							(mid -0.137521 0.162921)
							(end -0.1524 0.127)
						)
						(arc
							(start -0.1524 -0.127)
							(mid -0.137521 -0.162921)
							(end -0.1016 -0.1778)
						)
						(arc
							(start 0.1016 -0.1778)
							(mid 0.137521 -0.162921)
							(end 0.1524 -0.127)
						)
					)
					(width 0)
					(fill yes)
				)
			)
		)
	)
	(footprint ""
		(layer "B.Cu")
		(at 179.524152 -36.913058 90)
		(property "Reference" "C451"
			(at 0 0 90)
			(layer "B.SilkS")
			(hide yes)
			(effects
				(font
					(size 1.27 1.27)
				)
				(justify mirror)
			)
		)
		(property "Value" "SC1KP50V2KX-1GP"
			(at -1.1811 -2.7051 90)
			(unlocked yes)
			(layer "B.Fab")
			(hide yes)
			(effects
				(font
					(size 1.016 1.016)
					(thickness 0.1524)
				)
				(justify mirror)
			)
		)
		(property "Device Type" "C402H22"
			(at -1.1811 -4.2291 90)
			(unlocked yes)
			(layer "B.Fab")
			(hide yes)
			(effects
				(font
					(size 1.016 1.016)
					(thickness 0.1524)
				)
				(justify mirror)
			)
		)
		(duplicate_pad_numbers_are_jumpers no)
		(fp_rect
			(start 0.4318 0.9525)
			(end -0.4318 -0.9525)
			(stroke
				(width 0)
				(type default)
			)
			(fill no)
			(layer "B.CrtYd")
		)
		(fp_rect
			(start 0.4318 0.9525)
			(end -0.4318 -0.9525)
			(stroke
				(width 0)
				(type default)
			)
			(fill no)
			(layer "B.Fab")
		)
		(pad "1" smd custom
			(at 0 -0.4445 270)
			(size 0.1524 0.1524)
			(layers "B.Cu" "B.Mask" "B.Paste")
			(net "P0V975")
			(options
				(clearance outline)
				(anchor circle)
			)
			(primitives
				(gr_poly
					(pts
						(arc
							(start 0.3048 0.2032)
							(mid 0.275042 0.275042)
							(end 0.2032 0.3048)
						)
						(arc
							(start -0.2032 0.3048)
							(mid -0.275042 0.275042)
							(end -0.3048 0.2032)
						)
						(arc
							(start -0.3048 -0.2032)
							(mid -0.275042 -0.275042)
							(end -0.2032 -0.3048)
						)
						(arc
							(start 0.2032 -0.3048)
							(mid 0.275042 -0.275042)
							(end 0.3048 -0.2032)
						)
					)
					(width 0)
					(fill yes)
				)
			)
		)
		(pad "2" smd custom
			(at 0 0.4445 270)
			(size 0.1524 0.1524)
			(layers "B.Cu" "B.Mask" "B.Paste")
			(net "GND")
			(options
				(clearance outline)
				(anchor circle)
			)
			(primitives
				(gr_poly
					(pts
						(arc
							(start 0.3048 0.2032)
							(mid 0.275042 0.275042)
							(end 0.2032 0.3048)
						)
						(arc
							(start -0.2032 0.3048)
							(mid -0.275042 0.275042)
							(end -0.3048 0.2032)
						)
						(arc
							(start -0.3048 -0.2032)
							(mid -0.275042 -0.275042)
							(end -0.2032 -0.3048)
						)
						(arc
							(start 0.2032 -0.3048)
							(mid 0.275042 -0.275042)
							(end 0.3048 -0.2032)
						)
					)
					(width 0)
					(fill yes)
				)
			)
		)
	)
	(footprint ""
		(layer "B.Cu")
		(at 129.397252 -54.602634 90)
		(property "Reference" "C236"
			(at 0 0 90)
			(layer "B.SilkS")
			(hide yes)
			(effects
				(font
					(size 1.27 1.27)
				)
				(justify mirror)
			)
		)
		(property "Value" "SC1U6D3V1MX-GP"
			(at -1.9177 2.0193 90)
			(unlocked yes)
			(layer "B.Fab")
			(hide yes)
			(effects
				(font
					(size 1.016 1.016)
					(thickness 0.1524)
				)
				(justify mirror)
			)
		)
		(property "Device Type" "C0201H14"
			(at -1.9177 0.4953 90)
			(unlocked yes)
			(layer "B.Fab")
			(hide yes)
			(effects
				(font
					(size 1.016 1.016)
					(thickness 0.1524)
				)
				(justify mirror)
			)
		)
		(duplicate_pad_numbers_are_jumpers no)
		(fp_rect
			(start 0.1524 0.3048)
			(end -0.1524 -0.3048)
			(stroke
				(width 0)
				(type default)
			)
			(fill no)
			(layer "B.CrtYd")
		)
		(fp_poly
			(pts
				(xy 0.2794 0.6477) (xy 0.2794 -0.6477) (xy -0.2794 -0.6477) (xy -0.2794 -0.1905) (xy -0.1524 -0.1905)
				(xy -0.1524 -0.3048) (xy 0.1524 -0.3048) (xy 0.1524 0.3048) (xy -0.1524 0.3048) (xy -0.1524 -0.1778)
				(xy -0.2794 -0.1778) (xy -0.2794 0.6477)
			)
			(stroke
				(width 0)
				(type default)
			)
			(fill no)
			(layer "B.CrtYd")
		)
		(fp_rect
			(start 0.2794 0.6477)
			(end -0.2794 -0.6477)
			(stroke
				(width 0)
				(type default)
			)
			(fill no)
			(layer "B.Fab")
		)
		(pad "1" smd custom
			(at 0 -0.2794 270)
			(size 0.0762 0.0762)
			(layers "B.Cu" "B.Mask" "B.Paste")
			(net "GB_VDDA")
			(options
				(clearance outline)
				(anchor circle)
			)
			(primitives
				(gr_poly
					(pts
						(arc
							(start 0.1524 0.127)
							(mid 0.137521 0.162921)
							(end 0.1016 0.1778)
						)
						(arc
							(start -0.1016 0.1778)
							(mid -0.137521 0.162921)
							(end -0.1524 0.127)
						)
						(arc
							(start -0.1524 -0.127)
							(mid -0.137521 -0.162921)
							(end -0.1016 -0.1778)
						)
						(arc
							(start 0.1016 -0.1778)
							(mid 0.137521 -0.162921)
							(end 0.1524 -0.127)
						)
					)
					(width 0)
					(fill yes)
				)
			)
		)
		(pad "2" smd custom
			(at 0 0.2794 270)
			(size 0.0762 0.0762)
			(layers "B.Cu" "B.Mask" "B.Paste")
			(net "GND")
			(options
				(clearance outline)
				(anchor circle)
			)
			(primitives
				(gr_poly
					(pts
						(arc
							(start 0.1524 0.127)
							(mid 0.137521 0.162921)
							(end 0.1016 0.1778)
						)
						(arc
							(start -0.1016 0.1778)
							(mid -0.137521 0.162921)
							(end -0.1524 0.127)
						)
						(arc
							(start -0.1524 -0.127)
							(mid -0.137521 -0.162921)
							(end -0.1016 -0.1778)
						)
						(arc
							(start 0.1016 -0.1778)
							(mid 0.137521 -0.162921)
							(end 0.1524 -0.127)
						)
					)
					(width 0)
					(fill yes)
				)
			)
		)
	)
	(footprint ""
		(layer "B.Cu")
		(at 108.500164 -75.50023)
		(property "Reference" "TP19"
			(at 0 0 0)
			(layer "B.SilkS")
			(hide yes)
			(effects
				(font
					(size 1.27 1.27)
				)
				(justify mirror)
			)
		)
		(property "Value" "TPAD28-2-GP"
			(at 0.0127 -1.6637 0)
			(unlocked yes)
			(layer "B.Fab")
			(hide yes)
			(effects
				(font
					(size 1.016 1.016)
					(thickness 0.1524)
				)
				(justify mirror)
			)
		)
		(property "Device Type" "TPAD28"
			(at 0.0127 -3.1877 0)
			(unlocked yes)
			(layer "B.Fab")
			(hide yes)
			(effects
				(font
					(size 1.016 1.016)
					(thickness 0.1524)
				)
				(justify mirror)
			)
		)
		(duplicate_pad_numbers_are_jumpers no)
		(fp_poly
			(pts
				(arc
					(start 0.3556 0)
					(mid -0.3556 0)
					(end 0.3556 0)
				)
			)
			(stroke
				(width 0)
				(type default)
			)
			(fill no)
			(layer "B.CrtYd")
		)
		(fp_poly
			(pts
				(arc
					(start 0.6096 0)
					(mid -0.6096 0)
					(end 0.6096 0)
				)
			)
			(stroke
				(width 0)
				(type default)
			)
			(fill no)
			(layer "B.Fab")
		)
		(pad "1" smd circle
			(at 0 0 180)
			(size 0.7112 0.7112)
			(layers "B.Cu" "B.Mask" "B.Paste")
			(net "SXP_ACTIVE_1")
		)
	)
)
